(kicad_pcb
	(version 20260206)
	(generator "pcbnew")
	(generator_version "10.0")
	(general
		(thickness 1.6)
		(legacy_teardrops no)
	)
	(paper "A4")
	(title_block
		(title "Wiwynn_Tioga_Pass_MB.brd")
		(comment 1 "Tioga Pass / footprints 3137-3143 of 4770")
	)
	(layers
		(0 "F.Cu" signal "TOP")
		(4 "In1.Cu" signal "L2GND")
		(6 "In2.Cu" signal "L3")
		(8 "In3.Cu" signal "L4GND")
		(10 "In4.Cu" signal "L5")
		(12 "In5.Cu" signal "L6GND")
		(14 "In6.Cu" signal "L7VCC")
		(16 "In7.Cu" signal "L8VCC")
		(18 "In8.Cu" signal "L9GND")
		(20 "In9.Cu" signal "L10")
		(22 "In10.Cu" signal "L11GND")
		(24 "In11.Cu" signal "L12")
		(26 "In12.Cu" signal "L13GND")
		(2 "B.Cu" signal "BOTTOM")
		(9 "F.Adhes" user "F.Adhesive")
		(11 "B.Adhes" user "B.Adhesive")
		(13 "F.Paste" user "Package Geometry/Pastemask Top")
		(15 "B.Paste" user "Package Geometry/Pastemask Bottom")
		(5 "F.SilkS" user "Ref Des/Silkscreen Top")
		(7 "B.SilkS" user "Ref Des/Silkscreen Bottom")
		(1 "F.Mask" user "Board Geometry/Soldermask Top")
		(3 "B.Mask" user "Board Geometry/Soldermask Bottom")
		(17 "Dwgs.User" user "User.Drawings")
		(19 "Cmts.User" user "User.Comments")
		(21 "Eco1.User" user "User.Eco1")
		(23 "Eco2.User" user "User.Eco2")
		(25 "Edge.Cuts" user "Board Geometry/Outline")
		(27 "Margin" user)
		(31 "F.CrtYd" user "Package Geometry/Place Bound Top")
		(29 "B.CrtYd" user "Package Geometry/Place Bound Bottom")
		(35 "F.Fab" user "Ref Des/Assembly Top")
		(33 "B.Fab" user "Ref Des/Assembly Bottom")
	)
	(footprint ""
		(layer "B.Cu")
		(at 499.745 -153.1874 90)
		(property "Reference" "R6W36"
			(at 0.8382 -0.67818 90)
			(unlocked yes)
			(layer "B.SilkS")
			(effects
				(font
					(size 0.4064 0.254)
					(thickness 0.1524)
				)
				(justify left mirror)
			)
		)
		(property "Value" ""
			(at 0 0 90)
			(layer "B.Fab")
			(effects
				(font
					(size 1.27 1.27)
				)
				(justify mirror)
			)
		)
		(duplicate_pad_numbers_are_jumpers no)
		(fp_poly
			(pts
				(xy 0.2794 -0.1016) (xy -0.2794 -0.1016) (xy -0.2794 0.9906) (xy 0.2794 0.9906)
			)
			(stroke
				(width 0)
				(type default)
			)
			(fill no)
			(layer "B.CrtYd")
		)
		(fp_line
			(start 0.2794 -0.1016)
			(end 0.2794 0.9906)
			(stroke
				(width 0.1)
				(type default)
			)
			(layer "B.Fab")
		)
		(fp_line
			(start -0.2794 -0.1016)
			(end 0.2794 -0.1016)
			(stroke
				(width 0.1)
				(type default)
			)
			(layer "B.Fab")
		)
		(fp_line
			(start 0.2794 0.9906)
			(end -0.2794 0.9906)
			(stroke
				(width 0.1)
				(type default)
			)
			(layer "B.Fab")
		)
		(fp_line
			(start -0.2794 0.9906)
			(end -0.2794 -0.1016)
			(stroke
				(width 0.1)
				(type default)
			)
			(layer "B.Fab")
		)
		(pad "1" smd rect
			(at 0 0 270)
			(size 0.508 0.508)
			(layers "B.Cu" "B.Mask" "B.Paste")
			(net "SPA_MID_DBG1_TX_R")
		)
		(pad "2" smd rect
			(at 0 0.889 270)
			(size 0.508 0.508)
			(layers "B.Cu" "B.Mask" "B.Paste")
			(net "SPA_MID_DBG1_TX")
		)
		(zone
			(layer "B.Cu")
			(hatch none 0.5)
			(connect_pads
				(clearance 0)
			)
			(min_thickness 0.25)
			(keepout
				(tracks allowed)
				(vias not_allowed)
				(pads allowed)
				(copperpour not_allowed)
				(footprints allowed)
			)
			(placement
				(enabled no)
				(sheetname "")
			)
			(fill
				(thermal_gap 0.5)
				(thermal_bridge_width 0.5)
				(island_removal_mode 0)
			)
			(polygon
				(pts
					(xy 499.999 -153.4414) (xy 499.999 -152.9334) (xy 500.38 -152.9334) (xy 500.38 -153.4414)
				)
			)
		)
		(zone
			(layer "B.Cu")
			(hatch none 0.5)
			(connect_pads
				(clearance 0)
			)
			(min_thickness 0.25)
			(keepout
				(tracks not_allowed)
				(vias allowed)
				(pads allowed)
				(copperpour not_allowed)
				(footprints allowed)
			)
			(placement
				(enabled no)
				(sheetname "")
			)
			(fill
				(thermal_gap 0.5)
				(thermal_bridge_width 0.5)
				(island_removal_mode 0)
			)
			(polygon
				(pts
					(xy 500.38 -153.4414) (xy 500.38 -152.9334) (xy 499.999 -152.9334) (xy 499.999 -153.4414)
				)
			)
		)
	)
	(footprint ""
		(layer "B.Cu")
		(at 367.820956 -121.443242 -90)
		(property "Reference" "R785"
			(at 0.8382 -0.67818 270)
			(unlocked yes)
			(layer "B.SilkS")
			(effects
				(font
					(size 0.4064 0.254)
					(thickness 0.1524)
				)
				(justify left mirror)
			)
		)
		(property "Value" ""
			(at 0 0 90)
			(layer "B.Fab")
			(effects
				(font
					(size 1.27 1.27)
				)
				(justify mirror)
			)
		)
		(duplicate_pad_numbers_are_jumpers no)
		(fp_poly
			(pts
				(xy 0.2794 -0.1016) (xy -0.2794 -0.1016) (xy -0.2794 0.9906) (xy 0.2794 0.9906)
			)
			(stroke
				(width 0)
				(type default)
			)
			(fill no)
			(layer "B.CrtYd")
		)
		(fp_line
			(start -0.2794 0.9906)
			(end -0.2794 -0.1016)
			(stroke
				(width 0.1)
				(type default)
			)
			(layer "B.Fab")
		)
		(fp_line
			(start 0.2794 0.9906)
			(end -0.2794 0.9906)
			(stroke
				(width 0.1)
				(type default)
			)
			(layer "B.Fab")
		)
		(fp_line
			(start -0.2794 -0.1016)
			(end 0.2794 -0.1016)
			(stroke
				(width 0.1)
				(type default)
			)
			(layer "B.Fab")
		)
		(fp_line
			(start 0.2794 -0.1016)
			(end 0.2794 0.9906)
			(stroke
				(width 0.1)
				(type default)
			)
			(layer "B.Fab")
		)
		(pad "1" smd rect
			(at 0 0 90)
			(size 0.508 0.508)
			(layers "B.Cu" "B.Mask" "B.Paste")
			(net "P3E_CPU0_PE1_PCH_RXP<8>")
		)
		(pad "2" smd rect
			(at 0 0.889 90)
			(size 0.508 0.508)
			(layers "B.Cu" "B.Mask" "B.Paste")
			(net "P3E_CPU0_PE1_PCH_CON_RXP<8>")
		)
		(zone
			(layer "B.Cu")
			(hatch none 0.5)
			(connect_pads
				(clearance 0)
			)
			(min_thickness 0.25)
			(keepout
				(tracks not_allowed)
				(vias allowed)
				(pads allowed)
				(copperpour not_allowed)
				(footprints allowed)
			)
			(placement
				(enabled no)
				(sheetname "")
			)
			(fill
				(thermal_gap 0.5)
				(thermal_bridge_width 0.5)
				(island_removal_mode 0)
			)
			(polygon
				(pts
					(xy 367.185956 -121.189242) (xy 367.185956 -121.697242) (xy 367.566956 -121.697242) (xy 367.566956 -121.189242)
				)
			)
		)
		(zone
			(layer "B.Cu")
			(hatch none 0.5)
			(connect_pads
				(clearance 0)
			)
			(min_thickness 0.25)
			(keepout
				(tracks allowed)
				(vias not_allowed)
				(pads allowed)
				(copperpour not_allowed)
				(footprints allowed)
			)
			(placement
				(enabled no)
				(sheetname "")
			)
			(fill
				(thermal_gap 0.5)
				(thermal_bridge_width 0.5)
				(island_removal_mode 0)
			)
			(polygon
				(pts
					(xy 367.566956 -121.189242) (xy 367.566956 -121.697242) (xy 367.185956 -121.697242) (xy 367.185956 -121.189242)
				)
			)
		)
	)
	(footprint ""
		(layer "B.Cu")
		(at 430.85512 -141.101318 90)
		(property "Reference" "C2L51"
			(at 0 0 90)
			(layer "B.SilkS")
			(hide yes)
			(effects
				(font
					(size 1.27 1.27)
				)
				(justify mirror)
			)
		)
		(property "Value" ""
			(at 0 0 90)
			(layer "B.Fab")
			(effects
				(font
					(size 1.27 1.27)
				)
				(justify mirror)
			)
		)
		(duplicate_pad_numbers_are_jumpers no)
		(fp_poly
			(pts
				(xy -0.3048 -0.1016) (xy -0.3048 0.9906) (xy 0.3048 0.9906) (xy 0.3048 -0.1016)
			)
			(stroke
				(width 0)
				(type default)
			)
			(fill no)
			(layer "B.CrtYd")
		)
		(fp_line
			(start 0.3048 -0.1016)
			(end 0.3048 0.9906)
			(stroke
				(width 0.1)
				(type default)
			)
			(layer "B.Fab")
		)
		(fp_line
			(start -0.3048 -0.1016)
			(end 0.3048 -0.1016)
			(stroke
				(width 0.1)
				(type default)
			)
			(layer "B.Fab")
		)
		(fp_line
			(start 0.3048 0.9906)
			(end -0.3048 0.9906)
			(stroke
				(width 0.1)
				(type default)
			)
			(layer "B.Fab")
		)
		(fp_line
			(start -0.3048 0.9906)
			(end -0.3048 -0.1016)
			(stroke
				(width 0.1)
				(type default)
			)
			(layer "B.Fab")
		)
		(pad "1" smd rect
			(at 0 0 270)
			(size 0.508 0.508)
			(layers "B.Cu" "B.Mask" "B.Paste")
			(net "SATA6G_S1_TX_C_DN")
		)
		(pad "2" smd rect
			(at 0 0.889 270)
			(size 0.508 0.508)
			(layers "B.Cu" "B.Mask" "B.Paste")
			(net "SATA6G_S1_TX_DN")
		)
		(zone
			(layer "B.Cu")
			(hatch none 0.5)
			(connect_pads
				(clearance 0)
			)
			(min_thickness 0.25)
			(keepout
				(tracks allowed)
				(vias not_allowed)
				(pads allowed)
				(copperpour not_allowed)
				(footprints allowed)
			)
			(placement
				(enabled no)
				(sheetname "")
			)
			(fill
				(thermal_gap 0.5)
				(thermal_bridge_width 0.5)
				(island_removal_mode 0)
			)
			(polygon
				(pts
					(xy 431.10912 -141.355318) (xy 431.10912 -140.847318) (xy 431.49012 -140.847318) (xy 431.49012 -141.355318)
				)
			)
		)
		(zone
			(layer "B.Cu")
			(hatch none 0.5)
			(connect_pads
				(clearance 0)
			)
			(min_thickness 0.25)
			(keepout
				(tracks not_allowed)
				(vias allowed)
				(pads allowed)
				(copperpour not_allowed)
				(footprints allowed)
			)
			(placement
				(enabled no)
				(sheetname "")
			)
			(fill
				(thermal_gap 0.5)
				(thermal_bridge_width 0.5)
				(island_removal_mode 0)
			)
			(polygon
				(pts
					(xy 431.49012 -141.355318) (xy 431.49012 -140.847318) (xy 431.10912 -140.847318) (xy 431.10912 -141.355318)
				)
			)
		)
	)
	(footprint ""
		(layer "B.Cu")
		(at 384.4036 -109.855 -90)
		(property "Reference" "C3N11"
			(at 0 0 90)
			(layer "B.SilkS")
			(hide yes)
			(effects
				(font
					(size 1.27 1.27)
				)
				(justify mirror)
			)
		)
		(property "Value" ""
			(at 0 0 90)
			(layer "B.Fab")
			(effects
				(font
					(size 1.27 1.27)
				)
				(justify mirror)
			)
		)
		(duplicate_pad_numbers_are_jumpers no)
		(fp_rect
			(start 0.499872 1.522476)
			(end -0.500126 -0.277622)
			(stroke
				(width 0)
				(type default)
			)
			(fill no)
			(layer "B.CrtYd")
		)
		(fp_line
			(start -0.500126 1.522476)
			(end 0.499872 1.522476)
			(stroke
				(width 0.1)
				(type default)
			)
			(layer "B.Fab")
		)
		(fp_line
			(start 0.499872 1.522476)
			(end 0.499872 -0.277622)
			(stroke
				(width 0.1)
				(type default)
			)
			(layer "B.Fab")
		)
		(fp_line
			(start -0.500126 -0.277622)
			(end -0.500126 1.522476)
			(stroke
				(width 0.1)
				(type default)
			)
			(layer "B.Fab")
		)
		(fp_line
			(start 0.499872 -0.277622)
			(end -0.500126 -0.277622)
			(stroke
				(width 0.1)
				(type default)
			)
			(layer "B.Fab")
		)
		(pad "1" smd custom
			(at 0 0 180)
			(size 0.18415 0.18415)
			(layers "B.Cu" "B.Mask" "B.Paste")
			(net "PVNN_PCH_STBY")
			(options
				(clearance outline)
				(anchor circle)
			)
			(primitives
				(gr_poly
					(pts
						(arc
							(start -0.3683 0.2794)
							(mid -0.338542 0.351242)
							(end -0.2667 0.381)
						)
						(arc
							(start 0.2667 0.381)
							(mid 0.338542 0.351242)
							(end 0.3683 0.2794)
						)
						(arc
							(start 0.3683 -0.2794)
							(mid 0.338542 -0.351242)
							(end 0.2667 -0.381)
						)
						(arc
							(start -0.2667 -0.381)
							(mid -0.338542 -0.351242)
							(end -0.3683 -0.2794)
						)
					)
					(width 0)
					(fill yes)
				)
			)
		)
		(pad "2" smd custom
			(at 0 1.2446 180)
			(size 0.18415 0.18415)
			(layers "B.Cu" "B.Mask" "B.Paste")
			(net "GND")
			(options
				(clearance outline)
				(anchor circle)
			)
			(primitives
				(gr_poly
					(pts
						(arc
							(start -0.3683 0.2794)
							(mid -0.338542 0.351242)
							(end -0.2667 0.381)
						)
						(arc
							(start 0.2667 0.381)
							(mid 0.338542 0.351242)
							(end 0.3683 0.2794)
						)
						(arc
							(start 0.3683 -0.2794)
							(mid 0.338542 -0.351242)
							(end 0.2667 -0.381)
						)
						(arc
							(start -0.2667 -0.381)
							(mid -0.338542 -0.351242)
							(end -0.3683 -0.2794)
						)
					)
					(width 0)
					(fill yes)
				)
			)
		)
		(zone
			(layer "B.Cu")
			(hatch none 0.5)
			(connect_pads
				(clearance 0)
			)
			(min_thickness 0.25)
			(keepout
				(tracks allowed)
				(vias not_allowed)
				(pads allowed)
				(copperpour not_allowed)
				(footprints allowed)
			)
			(placement
				(enabled no)
				(sheetname "")
			)
			(fill
				(thermal_gap 0.5)
				(thermal_bridge_width 0.5)
				(island_removal_mode 0)
			)
			(polygon
				(pts
					(xy 383.5273 -109.474) (xy 384.0353 -109.474) (xy 384.0353 -110.236) (xy 383.5273 -110.236)
				)
			)
		)
		(zone
			(layer "B.Cu")
			(hatch none 0.5)
			(connect_pads
				(clearance 0)
			)
			(min_thickness 0.25)
			(keepout
				(tracks not_allowed)
				(vias allowed)
				(pads allowed)
				(copperpour not_allowed)
				(footprints allowed)
			)
			(placement
				(enabled no)
				(sheetname "")
			)
			(fill
				(thermal_gap 0.5)
				(thermal_bridge_width 0.5)
				(island_removal_mode 0)
			)
			(polygon
				(pts
					(xy 383.5273 -109.474) (xy 384.0353 -109.474) (xy 384.0353 -110.236) (xy 383.5273 -110.236)
				)
			)
		)
	)
	(footprint ""
		(layer "B.Cu")
		(at 386.842 -87.3125 180)
		(property "Reference" "R3N12"
			(at 0 0 0)
			(layer "B.SilkS")
			(hide yes)
			(effects
				(font
					(size 1.27 1.27)
				)
				(justify mirror)
			)
		)
		(property "Value" ""
			(at 0 0 0)
			(layer "B.Fab")
			(effects
				(font
					(size 1.27 1.27)
				)
				(justify mirror)
			)
		)
		(duplicate_pad_numbers_are_jumpers no)
		(fp_poly
			(pts
				(xy 0.2794 -0.1016) (xy -0.2794 -0.1016) (xy -0.2794 0.9906) (xy 0.2794 0.9906)
			)
			(stroke
				(width 0)
				(type default)
			)
			(fill no)
			(layer "B.CrtYd")
		)
		(fp_line
			(start 0.2794 0.9906)
			(end -0.2794 0.9906)
			(stroke
				(width 0.1)
				(type default)
			)
			(layer "B.Fab")
		)
		(fp_line
			(start 0.2794 -0.1016)
			(end 0.2794 0.9906)
			(stroke
				(width 0.1)
				(type default)
			)
			(layer "B.Fab")
		)
		(fp_line
			(start -0.2794 0.9906)
			(end -0.2794 -0.1016)
			(stroke
				(width 0.1)
				(type default)
			)
			(layer "B.Fab")
		)
		(fp_line
			(start -0.2794 -0.1016)
			(end 0.2794 -0.1016)
			(stroke
				(width 0.1)
				(type default)
			)
			(layer "B.Fab")
		)
		(pad "1" smd rect
			(at 0 0)
			(size 0.508 0.508)
			(layers "B.Cu" "B.Mask" "B.Paste")
			(net "P3V3_STBY")
		)
		(pad "2" smd rect
			(at 0 0.889)
			(size 0.508 0.508)
			(layers "B.Cu" "B.Mask" "B.Paste")
			(net "FM_MP_PS_FAIL_N")
		)
		(zone
			(layer "B.Cu")
			(hatch none 0.5)
			(connect_pads
				(clearance 0)
			)
			(min_thickness 0.25)
			(keepout
				(tracks not_allowed)
				(vias allowed)
				(pads allowed)
				(copperpour not_allowed)
				(footprints allowed)
			)
			(placement
				(enabled no)
				(sheetname "")
			)
			(fill
				(thermal_gap 0.5)
				(thermal_bridge_width 0.5)
				(island_removal_mode 0)
			)
			(polygon
				(pts
					(xy 386.588 -87.9475) (xy 387.096 -87.9475) (xy 387.096 -87.5665) (xy 386.588 -87.5665)
				)
			)
		)
		(zone
			(layer "B.Cu")
			(hatch none 0.5)
			(connect_pads
				(clearance 0)
			)
			(min_thickness 0.25)
			(keepout
				(tracks allowed)
				(vias not_allowed)
				(pads allowed)
				(copperpour not_allowed)
				(footprints allowed)
			)
			(placement
				(enabled no)
				(sheetname "")
			)
			(fill
				(thermal_gap 0.5)
				(thermal_bridge_width 0.5)
				(island_removal_mode 0)
			)
			(polygon
				(pts
					(xy 386.588 -87.5665) (xy 387.096 -87.5665) (xy 387.096 -87.9475) (xy 386.588 -87.9475)
				)
			)
		)
	)
	(footprint ""
		(layer "B.Cu")
		(at 45.212 -89.408 -90)
		(property "Reference" "C9N24"
			(at -0.35433 -3.937 0)
			(unlocked yes)
			(layer "B.SilkS")
			(effects
				(font
					(size 0.7874 0.5842)
					(thickness 0.1524)
				)
				(justify mirror)
			)
		)
		(property "Value" ""
			(at 0 0 90)
			(layer "B.Fab")
			(effects
				(font
					(size 1.27 1.27)
				)
				(justify mirror)
			)
		)
		(duplicate_pad_numbers_are_jumpers no)
		(fp_line
			(start -2.286 7.366)
			(end -1.600708 7.366)
			(stroke
				(width 0.1524)
				(type default)
			)
			(layer "B.SilkS")
		)
		(fp_line
			(start -2.286 7.366)
			(end -2.286 1.63195)
			(stroke
				(width 0.1524)
				(type default)
			)
			(layer "B.SilkS")
		)
		(fp_line
			(start 2.286 7.366)
			(end 1.60147 7.366)
			(stroke
				(width 0.1524)
				(type default)
			)
			(layer "B.SilkS")
		)
		(fp_line
			(start 2.286 7.366)
			(end 2.286 1.632712)
			(stroke
				(width 0.1524)
				(type default)
			)
			(layer "B.SilkS")
		)
		(fp_line
			(start -2.504948 1.633728)
			(end -1.6002 1.633728)
			(stroke
				(width 0.1524)
				(type default)
			)
			(layer "B.SilkS")
		)
		(fp_line
			(start 2.563114 1.633728)
			(end 1.6002 1.633728)
			(stroke
				(width 0.1524)
				(type default)
			)
			(layer "B.SilkS")
		)
		(fp_line
			(start -2.504948 -1.616456)
			(end -2.504948 1.633728)
			(stroke
				(width 0.1524)
				(type default)
			)
			(layer "B.SilkS")
		)
		(fp_line
			(start -1.6002 -1.616456)
			(end -2.504948 -1.616456)
			(stroke
				(width 0.1524)
				(type default)
			)
			(layer "B.SilkS")
		)
		(fp_line
			(start 1.6002 -1.616456)
			(end 2.563114 -1.616456)
			(stroke
				(width 0.1524)
				(type default)
			)
			(layer "B.SilkS")
		)
		(fp_line
			(start 2.563114 -1.616456)
			(end 2.563114 1.633728)
			(stroke
				(width 0.1524)
				(type default)
			)
			(layer "B.SilkS")
		)
		(fp_rect
			(start 2.286 7.366)
			(end -2.286 -0.254)
			(stroke
				(width 0)
				(type default)
			)
			(fill no)
			(layer "B.CrtYd")
		)
		(fp_line
			(start -2.286 7.366)
			(end 2.286 7.366)
			(stroke
				(width 0.1)
				(type default)
			)
			(layer "B.Fab")
		)
		(fp_line
			(start 2.286 7.366)
			(end 2.286 -0.254)
			(stroke
				(width 0.1)
				(type default)
			)
			(layer "B.Fab")
		)
		(fp_line
			(start -2.286 -0.254)
			(end -2.286 7.366)
			(stroke
				(width 0.1)
				(type default)
			)
			(layer "B.Fab")
		)
		(fp_line
			(start 2.286 -0.254)
			(end -2.286 -0.254)
			(stroke
				(width 0.1)
				(type default)
			)
			(layer "B.Fab")
		)
		(pad "1" smd rect
			(at 0 0 90)
			(size 2.54 3.048)
			(layers "B.Cu" "B.Mask" "B.Paste")
			(net "PVCCIN_CPU1")
		)
		(pad "2" smd rect
			(at 0 7.112 90)
			(size 2.54 3.048)
			(layers "B.Cu" "B.Mask" "B.Paste")
			(net "GND")
		)
	)
	(footprint ""
		(layer "B.Cu")
		(at 327.158096 -54.597808 90)
		(property "Reference" "R5W1"
			(at 0.8382 -0.67818 90)
			(unlocked yes)
			(layer "B.SilkS")
			(effects
				(font
					(size 0.4064 0.254)
					(thickness 0.1524)
				)
				(justify left mirror)
			)
		)
		(property "Value" ""
			(at 0 0 90)
			(layer "B.Fab")
			(effects
				(font
					(size 1.27 1.27)
				)
				(justify mirror)
			)
		)
		(duplicate_pad_numbers_are_jumpers no)
		(fp_poly
			(pts
				(xy 0.2794 -0.1016) (xy -0.2794 -0.1016) (xy -0.2794 0.9906) (xy 0.2794 0.9906)
			)
			(stroke
				(width 0)
				(type default)
			)
			(fill no)
			(layer "B.CrtYd")
		)
		(fp_line
			(start 0.2794 -0.1016)
			(end 0.2794 0.9906)
			(stroke
				(width 0.1)
				(type default)
			)
			(layer "B.Fab")
		)
		(fp_line
			(start -0.2794 -0.1016)
			(end 0.2794 -0.1016)
			(stroke
				(width 0.1)
				(type default)
			)
			(layer "B.Fab")
		)
		(fp_line
			(start 0.2794 0.9906)
			(end -0.2794 0.9906)
			(stroke
				(width 0.1)
				(type default)
			)
			(layer "B.Fab")
		)
		(fp_line
			(start -0.2794 0.9906)
			(end -0.2794 -0.1016)
			(stroke
				(width 0.1)
				(type default)
			)
			(layer "B.Fab")
		)
		(pad "1" smd rect
			(at 0 0 270)
			(size 0.508 0.508)
			(layers "B.Cu" "B.Mask" "B.Paste")
			(net "P1V8_MCP_CPU0")
		)
		(pad "2" smd rect
			(at 0 0.889 270)
			(size 0.508 0.508)
			(layers "B.Cu" "B.Mask" "B.Paste")
			(net "JTAG_MCP_CPU0_TDI_R")
		)
		(zone
			(layer "B.Cu")
			(hatch none 0.5)
			(connect_pads
				(clearance 0)
			)
			(min_thickness 0.25)
			(keepout
				(tracks allowed)
				(vias not_allowed)
				(pads allowed)
				(copperpour not_allowed)
				(footprints allowed)
			)
			(placement
				(enabled no)
				(sheetname "")
			)
			(fill
				(thermal_gap 0.5)
				(thermal_bridge_width 0.5)
				(island_removal_mode 0)
			)
			(polygon
				(pts
					(xy 327.412096 -54.851808) (xy 327.412096 -54.343808) (xy 327.793096 -54.343808) (xy 327.793096 -54.851808)
				)
			)
		)
		(zone
			(layer "B.Cu")
			(hatch none 0.5)
			(connect_pads
				(clearance 0)
			)
			(min_thickness 0.25)
			(keepout
				(tracks not_allowed)
				(vias allowed)
				(pads allowed)
				(copperpour not_allowed)
				(footprints allowed)
			)
			(placement
				(enabled no)
				(sheetname "")
			)
			(fill
				(thermal_gap 0.5)
				(thermal_bridge_width 0.5)
				(island_removal_mode 0)
			)
			(polygon
				(pts
					(xy 327.793096 -54.851808) (xy 327.793096 -54.343808) (xy 327.412096 -54.343808) (xy 327.412096 -54.851808)
				)
			)
		)
	)
)
